#ISCELL
  mstr_misc prelim *
  *
#ISCELL
  mstr_symbols design_note *
  *
#ISCELL
  mstr_symbols intel_corp_bpage *
  *
#CELL
  chpset_lib skx_ext_b *
  page70_i10
#ISCELL
  mstr_standard offpage *
  page70_i11
#ISCELL
  mstr_symbols vcc_core *
  page70_i12
#ISCELL
  mstr_symbols vcc_core *
  page70_i13
#ISCELL
  mstr_symbols vcc_core *
  page70_i15
#ISCELL
  mstr_standard offpage *
  page70_i7
#CELL
  chpset_lib skx_ext_b *
  page70_i9
